# S9S_MB_2U (Grand Teton) — schematic netlist excerpt (pin names and nets, part order shuffled) for the footprints in the layout excerpt that follows; sources: Cadence DE-HDL packaged netlist, KiCad conversion of 03242023_DA0F0TMBIJ0_F0T_Motherboard_J_brd_V01_OCP.brd

C2041  Q_CAP  1UF 25V 10% X6S  pkg C0402  page 152 : A = RST_USB_HUB_R_N ; B = GND
PC2089  Q_CAP  6800PF 50V 10% X7R  pkg C0402  page 156 : A = P3V3_OCP_GATE_PU202_1 ; B = GND

(kicad_pcb
	(version 20260206)
	(generator "pcbnew")
	(generator_version "10.0")
	(general
		(thickness 1.6)
		(legacy_teardrops no)
	)
	(paper "A4")
	(title_block
		(title "03242023_DA0F0TMBIJ0_F0T_Motherboard_J_brd_V01_OCP.brd")
		(comment 1 "Grand Teton / footprints 813-814 of 6105")
	)
	(layers
		(0 "F.Cu" signal "TOP")
		(4 "In1.Cu" signal "GND")
		(6 "In2.Cu" signal "IN1")
		(8 "In3.Cu" signal "GND1")
		(10 "In4.Cu" signal "IN2")
		(12 "In5.Cu" signal "GND2")
		(14 "In6.Cu" signal "IN3")
		(16 "In7.Cu" signal "GND3")
		(18 "In8.Cu" signal "VCC")
		(20 "In9.Cu" signal "VCC1")
		(22 "In10.Cu" signal "GND4")
		(24 "In11.Cu" signal "IN4")
		(26 "In12.Cu" signal "GND5")
		(28 "In13.Cu" signal "IN5")
		(30 "In14.Cu" signal "GND6")
		(32 "In15.Cu" signal "IN6")
		(34 "In16.Cu" signal "GND7")
		(2 "B.Cu" signal "BOTTOM")
		(9 "F.Adhes" user "F.Adhesive")
		(11 "B.Adhes" user "B.Adhesive")
		(13 "F.Paste" user "Package Geometry/Pastemask Top")
		(15 "B.Paste" user "Package Geometry/Pastemask Bottom")
		(5 "F.SilkS" user "Ref Des/Silkscreen Top")
		(7 "B.SilkS" user "Ref Des/Silkscreen Bottom")
		(1 "F.Mask" user "Board Geometry/Soldermask Top")
		(3 "B.Mask" user "Board Geometry/Soldermask Bottom")
		(17 "Dwgs.User" user "User.Drawings")
		(19 "Cmts.User" user "User.Comments")
		(21 "Eco1.User" user "User.Eco1")
		(23 "Eco2.User" user "User.Eco2")
		(25 "Edge.Cuts" user "Board Geometry/Outline")
		(27 "Margin" user)
		(31 "F.CrtYd" user "Package Geometry/Place Bound Top")
		(29 "B.CrtYd" user "Package Geometry/Place Bound Bottom")
		(35 "F.Fab" user "Ref Des/Assembly Top")
		(33 "B.Fab" user "Ref Des/Assembly Bottom")
	)
	(footprint ""
		(layer "F.Cu")
		(at 11.895836 -92.687648 -90)
		(property "Reference" "C2041"
			(at 0 0 270)
			(layer "F.SilkS")
			(hide yes)
			(effects
				(font
					(size 1.27 1.27)
				)
			)
		)
		(property "Value" ""
			(at 0 0 270)
			(layer "F.Fab")
			(effects
				(font
					(size 1.27 1.27)
				)
			)
		)
		(duplicate_pad_numbers_are_jumpers no)
		(fp_line
			(start -0.7874 0.4064)
			(end -0.7874 -0.4064)
			(stroke
				(width 0.1524)
				(type default)
			)
			(layer "F.SilkS")
		)
		(fp_line
			(start 0.7874 0.4064)
			(end -0.7874 0.4064)
			(stroke
				(width 0.1524)
				(type default)
			)
			(layer "F.SilkS")
		)
		(fp_line
			(start -0.7874 -0.4064)
			(end 0.7874 -0.4064)
			(stroke
				(width 0.1524)
				(type default)
			)
			(layer "F.SilkS")
		)
		(fp_line
			(start 0.7874 -0.4064)
			(end 0.7874 0.4064)
			(stroke
				(width 0.1524)
				(type default)
			)
			(layer "F.SilkS")
		)
		(fp_line
			(start -0.67945 0.3048)
			(end -0.67945 -0.305054)
			(stroke
				(width 0.1)
				(type default)
			)
			(layer "F.Fab")
		)
		(fp_line
			(start -0.12065 0.3048)
			(end -0.67945 0.3048)
			(stroke
				(width 0.1)
				(type default)
			)
			(layer "F.Fab")
		)
		(fp_line
			(start 0.120396 0.3048)
			(end 0.120396 0.2794)
			(stroke
				(width 0.1)
				(type default)
			)
			(layer "F.Fab")
		)
		(fp_line
			(start 0.67945 0.3048)
			(end 0.120396 0.3048)
			(stroke
				(width 0.1)
				(type default)
			)
			(layer "F.Fab")
		)
		(fp_line
			(start -0.12065 0.2794)
			(end -0.12065 0.3048)
			(stroke
				(width 0.1)
				(type default)
			)
			(layer "F.Fab")
		)
		(fp_line
			(start 0.120396 0.2794)
			(end -0.12065 0.2794)
			(stroke
				(width 0.1)
				(type default)
			)
			(layer "F.Fab")
		)
		(fp_line
			(start -0.12065 -0.2794)
			(end 0.12065 -0.2794)
			(stroke
				(width 0.1)
				(type default)
			)
			(layer "F.Fab")
		)
		(fp_line
			(start 0.12065 -0.2794)
			(end 0.12065 -0.3048)
			(stroke
				(width 0.1)
				(type default)
			)
			(layer "F.Fab")
		)
		(fp_line
			(start 0.12065 -0.3048)
			(end 0.67945 -0.3048)
			(stroke
				(width 0.1)
				(type default)
			)
			(layer "F.Fab")
		)
		(fp_line
			(start 0.67945 -0.3048)
			(end 0.67945 0.3048)
			(stroke
				(width 0.1)
				(type default)
			)
			(layer "F.Fab")
		)
		(fp_line
			(start -0.67945 -0.305054)
			(end -0.12065 -0.305054)
			(stroke
				(width 0.1)
				(type default)
			)
			(layer "F.Fab")
		)
		(fp_line
			(start -0.12065 -0.305054)
			(end -0.12065 -0.2794)
			(stroke
				(width 0.1)
				(type default)
			)
			(layer "F.Fab")
		)
		(pad "1" smd circle
			(at -0.40005 0 270)
			(size 0 0)
			(layers "F.Cu" "F.Mask" "F.Paste")
			(net "RST_USB_HUB_R_N")
		)
		(pad "2" smd circle
			(at 0.40005 0 270)
			(size 0 0)
			(layers "F.Cu" "F.Mask" "F.Paste")
			(net "GND")
		)
	)
	(footprint ""
		(layer "F.Cu")
		(at 434.448204 -103.927402 -90)
		(property "Reference" "PC2089"
			(at 0 0 270)
			(layer "F.SilkS")
			(hide yes)
			(effects
				(font
					(size 1.27 1.27)
				)
			)
		)
		(property "Value" ""
			(at 0 0 270)
			(layer "F.Fab")
			(effects
				(font
					(size 1.27 1.27)
				)
			)
		)
		(duplicate_pad_numbers_are_jumpers no)
		(fp_line
			(start -0.7874 0.4064)
			(end -0.7874 -0.4064)
			(stroke
				(width 0.1524)
				(type default)
			)
			(layer "F.SilkS")
		)
		(fp_line
			(start 0.7874 0.4064)
			(end -0.7874 0.4064)
			(stroke
				(width 0.1524)
				(type default)
			)
			(layer "F.SilkS")
		)
		(fp_line
			(start -0.7874 -0.4064)
			(end 0.7874 -0.4064)
			(stroke
				(width 0.1524)
				(type default)
			)
			(layer "F.SilkS")
		)
		(fp_line
			(start 0.7874 -0.4064)
			(end 0.7874 0.4064)
			(stroke
				(width 0.1524)
				(type default)
			)
			(layer "F.SilkS")
		)
		(fp_line
			(start -0.67945 0.3048)
			(end -0.67945 -0.305054)
			(stroke
				(width 0.1)
				(type default)
			)
			(layer "F.Fab")
		)
		(fp_line
			(start -0.12065 0.3048)
			(end -0.67945 0.3048)
			(stroke
				(width 0.1)
				(type default)
			)
			(layer "F.Fab")
		)
		(fp_line
			(start 0.120396 0.3048)
			(end 0.120396 0.2794)
			(stroke
				(width 0.1)
				(type default)
			)
			(layer "F.Fab")
		)
		(fp_line
			(start 0.67945 0.3048)
			(end 0.120396 0.3048)
			(stroke
				(width 0.1)
				(type default)
			)
			(layer "F.Fab")
		)
		(fp_line
			(start -0.12065 0.2794)
			(end -0.12065 0.3048)
			(stroke
				(width 0.1)
				(type default)
			)
			(layer "F.Fab")
		)
		(fp_line
			(start 0.120396 0.2794)
			(end -0.12065 0.2794)
			(stroke
				(width 0.1)
				(type default)
			)
			(layer "F.Fab")
		)
		(fp_line
			(start -0.12065 -0.2794)
			(end 0.12065 -0.2794)
			(stroke
				(width 0.1)
				(type default)
			)
			(layer "F.Fab")
		)
		(fp_line
			(start 0.12065 -0.2794)
			(end 0.12065 -0.3048)
			(stroke
				(width 0.1)
				(type default)
			)
			(layer "F.Fab")
		)
		(fp_line
			(start 0.12065 -0.3048)
			(end 0.67945 -0.3048)
			(stroke
				(width 0.1)
				(type default)
			)
			(layer "F.Fab")
		)
		(fp_line
			(start 0.67945 -0.3048)
			(end 0.67945 0.3048)
			(stroke
				(width 0.1)
				(type default)
			)
			(layer "F.Fab")
		)
		(fp_line
			(start -0.67945 -0.305054)
			(end -0.12065 -0.305054)
			(stroke
				(width 0.1)
				(type default)
			)
			(layer "F.Fab")
		)
		(fp_line
			(start -0.12065 -0.305054)
			(end -0.12065 -0.2794)
			(stroke
				(width 0.1)
				(type default)
			)
			(layer "F.Fab")
		)
		(pad "1" smd circle
			(at -0.40005 0 270)
			(size 0 0)
			(layers "F.Cu" "F.Mask" "F.Paste")
			(net "P3V3_OCP_GATE_PU202_1")
		)
		(pad "2" smd circle
			(at 0.40005 0 270)
			(size 0 0)
			(layers "F.Cu" "F.Mask" "F.Paste")
			(net "GND")
		)
	)
)
